(kicad_pcb
	(version 20241229)
	(generator "pcbnew")
	(generator_version "9.0")
	(general
		(thickness 1.62)
		(legacy_teardrops no)
	)
	(paper "A3")
	(title_block
		(title "COM Express 7 Baseboard")
		(date "2025-02-04")
		(rev "1.1.2")
		(company "Antmicro Ltd")
		(comment 1 "www.antmicro.com")
		(comment 9 "footprints 321-322 of 802")
	)
	(layers
		(0 "F.Cu" signal)
		(4 "In1.Cu" signal)
		(6 "In2.Cu" signal)
		(8 "In3.Cu" signal)
		(10 "In4.Cu" signal)
		(12 "In5.Cu" signal)
		(14 "In6.Cu" signal)
		(2 "B.Cu" signal)
		(9 "F.Adhes" user "F.Adhesive")
		(11 "B.Adhes" user "B.Adhesive")
		(13 "F.Paste" user)
		(15 "B.Paste" user)
		(5 "F.SilkS" user "F.Silkscreen")
		(7 "B.SilkS" user "B.Silkscreen")
		(1 "F.Mask" user)
		(3 "B.Mask" user)
		(17 "Dwgs.User" user "User.Drawings")
		(19 "Cmts.User" user "User.Comments")
		(21 "Eco1.User" user "User.Eco1")
		(23 "Eco2.User" user "User.Eco2")
		(25 "Edge.Cuts" user)
		(27 "Margin" user)
		(31 "F.CrtYd" user "F.Courtyard")
		(29 "B.CrtYd" user "B.Courtyard")
		(35 "F.Fab" user)
		(33 "B.Fab" user)
	)
	(footprint "antmicro-footprints:R_0402_1005Metric"
		(layer "F.Cu")
		(at 143.45 83.06 180)
		(descr "Resistor SMD 0402")
		(tags "resistor SMD 0402")
		(property "Reference" "R137"
			(at 0.85 -0.5 0)
			(layer "F.SilkS")
			(effects
				(font
					(size 0.7 0.7)
					(thickness 0.15)
				)
				(justify right bottom)
			)
		)
		(property "Value" "R_0R_0402"
			(at -1.011843 1.772047 0)
			(layer "F.Fab")
			(effects
				(font
					(size 0.7 0.7)
					(thickness 0.15)
				)
				(justify right bottom)
			)
		)
		(property "Datasheet" "https://industrial.panasonic.com/cdbs/www-data/pdf/RDA0000/AOA0000C301.pdf"
			(at 0 0 180)
			(layer "F.Fab")
			(hide yes)
			(effects
				(font
					(size 1.27 1.27)
					(thickness 0.15)
				)
			)
		)
		(property "Author" "Antmicro"
			(at 286.9 166.12 0)
			(layer "F.Fab")
			(hide yes)
			(effects
				(font
					(size 1 1)
					(thickness 0.15)
				)
			)
		)
		(property "Current" "1A"
			(at 286.9 166.12 0)
			(layer "F.Fab")
			(hide yes)
			(effects
				(font
					(size 1 1)
					(thickness 0.15)
				)
			)
		)
		(property "License" "Apache-2.0"
			(at 286.9 166.12 0)
			(layer "F.Fab")
			(hide yes)
			(effects
				(font
					(size 1 1)
					(thickness 0.15)
				)
			)
		)
		(property "MPN" "ERJ2GE0R00X"
			(at 286.9 166.12 0)
			(layer "F.Fab")
			(hide yes)
			(effects
				(font
					(size 1 1)
					(thickness 0.15)
				)
			)
		)
		(property "Manufacturer" "Panasonic"
			(at 286.9 166.12 0)
			(layer "F.Fab")
			(hide yes)
			(effects
				(font
					(size 1 1)
					(thickness 0.15)
				)
			)
		)
		(property "Public" "False"
			(at 286.9 166.12 0)
			(layer "F.Fab")
			(hide yes)
			(effects
				(font
					(size 1 1)
					(thickness 0.15)
				)
			)
		)
		(property "Tolerance" ""
			(at 286.9 166.12 0)
			(layer "F.Fab")
			(hide yes)
			(effects
				(font
					(size 1 1)
					(thickness 0.15)
				)
			)
		)
		(property "Val" "0R"
			(at 286.9 166.12 0)
			(layer "F.Fab")
			(hide yes)
			(effects
				(font
					(size 1 1)
					(thickness 0.15)
				)
			)
		)
		(sheetname "M.2 key E")
		(sheetfile "m2keye.kicad_sch")
		(attr smd)
		(fp_rect
			(start -0.925 -0.47)
			(end 0.925 0.47)
			(stroke
				(width 0.05)
				(type default)
			)
			(fill no)
			(layer "F.CrtYd")
		)
		(fp_rect
			(start -0.5 -0.25)
			(end 0.5 0.25)
			(stroke
				(width 0.15)
				(type solid)
			)
			(fill no)
			(layer "F.Fab")
		)
		(pad "1" smd roundrect
			(at -0.48 0 180)
			(size 0.59 0.64)
			(layers "F.Cu" "F.Mask" "F.Paste")
			(roundrect_rratio 0.25)
			(net 38 "Net-(J100-SUSCLK)")
			(pintype "passive")
			(teardrops
				(best_length_ratio 0.2)
				(max_length 1)
				(best_width_ratio 0.9)
				(max_width 2)
				(curved_edges yes)
				(filter_ratio 0.9)
				(enabled yes)
				(allow_two_segments yes)
				(prefer_zone_connections yes)
			)
		)
		(pad "2" smd roundrect
			(at 0.48 0 180)
			(size 0.59 0.64)
			(layers "F.Cu" "F.Mask" "F.Paste")
			(roundrect_rratio 0.25)
			(net 587 "/M.2 key E/SUSCLK")
			(pintype "passive")
			(teardrops
				(best_length_ratio 0.2)
				(max_length 1)
				(best_width_ratio 0.9)
				(max_width 2)
				(curved_edges yes)
				(filter_ratio 0.9)
				(enabled yes)
				(allow_two_segments yes)
				(prefer_zone_connections yes)
			)
		)
	)
	(footprint "antmicro-footprints:R_0402_1005Metric"
		(layer "F.Cu")
		(at 143 133.88)
		(descr "Resistor SMD 0402")
		(tags "resistor SMD 0402")
		(property "Reference" "R271"
			(at -3.6 0.43 0)
			(layer "F.SilkS")
			(effects
				(font
					(size 0.7 0.7)
					(thickness 0.15)
				)
				(justify left bottom)
			)
		)
		(property "Value" "R_10k_0402"
			(at -1.011843 1.772047 0)
			(layer "F.Fab")
			(effects
				(font
					(size 0.7 0.7)
					(thickness 0.15)
				)
				(justify left bottom)
			)
		)
		(property "Datasheet" "https://www.bourns.com/docs/product-datasheets/cr.pdf"
			(at 0 0 0)
			(layer "F.Fab")
			(hide yes)
			(effects
				(font
					(size 1.27 1.27)
					(thickness 0.15)
				)
			)
		)
		(property "Author" "Antmicro"
			(at 0 0 0)
			(layer "F.Fab")
			(hide yes)
			(effects
				(font
					(size 1 1)
					(thickness 0.15)
				)
			)
		)
		(property "License" "Apache-2.0"
			(at 0 0 0)
			(layer "F.Fab")
			(hide yes)
			(effects
				(font
					(size 1 1)
					(thickness 0.15)
				)
			)
		)
		(property "MPN" "CR0402-FX-1002GLF"
			(at 0 0 0)
			(layer "F.Fab")
			(hide yes)
			(effects
				(font
					(size 1 1)
					(thickness 0.15)
				)
			)
		)
		(property "Manufacturer" "Bourns"
			(at 0 0 0)
			(layer "F.Fab")
			(hide yes)
			(effects
				(font
					(size 1 1)
					(thickness 0.15)
				)
			)
		)
		(property "Public" "False"
			(at 0 0 0)
			(layer "F.Fab")
			(hide yes)
			(effects
				(font
					(size 1 1)
					(thickness 0.15)
				)
			)
		)
		(property "Tolerance" "1%"
			(at 0 0 0)
			(layer "F.Fab")
			(hide yes)
			(effects
				(font
					(size 1 1)
					(thickness 0.15)
				)
			)
		)
		(property "Val" "10k"
			(at 0 0 0)
			(layer "F.Fab")
			(hide yes)
			(effects
				(font
					(size 1 1)
					(thickness 0.15)
				)
			)
		)
		(sheetname "KR to SFI #1")
		(sheetfile "kr_sfi.kicad_sch")
		(attr smd)
		(fp_rect
			(start -0.925 -0.47)
			(end 0.925 0.47)
			(stroke
				(width 0.05)
				(type default)
			)
			(fill no)
			(layer "F.CrtYd")
		)
		(fp_rect
			(start -0.5 -0.25)
			(end 0.5 0.25)
			(stroke
				(width 0.15)
				(type solid)
			)
			(fill no)
			(layer "F.Fab")
		)
		(pad "1" smd roundrect
			(at -0.48 0)
			(size 0.59 0.64)
			(layers "F.Cu" "F.Mask" "F.Paste")
			(roundrect_rratio 0.25)
			(net 1 "GND")
			(pintype "passive")
			(teardrops
				(best_length_ratio 0.2)
				(max_length 1)
				(best_width_ratio 0.9)
				(max_width 2)
				(curved_edges yes)
				(filter_ratio 0.9)
				(enabled yes)
				(allow_two_segments yes)
				(prefer_zone_connections yes)
			)
		)
		(pad "2" smd roundrect
			(at 0.48 0)
			(size 0.59 0.64)
			(layers "F.Cu" "F.Mask" "F.Paste")
			(roundrect_rratio 0.25)
			(net 663 "Net-(U43C-ST)")
			(pintype "passive")
			(teardrops
				(best_length_ratio 0.2)
				(max_length 1)
				(best_width_ratio 0.9)
				(max_width 2)
				(curved_edges yes)
				(filter_ratio 0.9)
				(enabled yes)
				(allow_two_segments yes)
				(prefer_zone_connections yes)
			)
		)
	)
)
